# BASEBOARD_FAB2 (Tioga Pass) — schematic netlist excerpt (pin names and nets, part order shuffled) for the footprints in the layout excerpt that follows; sources: Cadence DE-HDL packaged netlist, KiCad conversion of Wiwynn_Tioga_Pass_MB.brd

RF6  RES  1.0K 0.1% CHIP  pkg 0402  page 201 : A = VR_PVSA_CPU0_BIREF1 ; B = ISENSE_PVSA_CPU0_IMON
R9B9  RES  1.00K 1% CHIP  pkg 0402  page 113 : A = JTAG_MCP_TCK ; B = GND
C5D48  CAP_A  22.0UF 4V 20% X6S  pkg 0603V  page 42 : A = PVCCMCP_CPU0 ; B = GND

(kicad_pcb
	(version 20260206)
	(generator "pcbnew")
	(generator_version "10.0")
	(general
		(thickness 1.6)
		(legacy_teardrops no)
	)
	(paper "A4")
	(title_block
		(title "Wiwynn_Tioga_Pass_MB.brd")
		(comment 1 "Tioga Pass / footprints 1571-1573 of 4770")
	)
	(layers
		(0 "F.Cu" signal "TOP")
		(4 "In1.Cu" signal "L2GND")
		(6 "In2.Cu" signal "L3")
		(8 "In3.Cu" signal "L4GND")
		(10 "In4.Cu" signal "L5")
		(12 "In5.Cu" signal "L6GND")
		(14 "In6.Cu" signal "L7VCC")
		(16 "In7.Cu" signal "L8VCC")
		(18 "In8.Cu" signal "L9GND")
		(20 "In9.Cu" signal "L10")
		(22 "In10.Cu" signal "L11GND")
		(24 "In11.Cu" signal "L12")
		(26 "In12.Cu" signal "L13GND")
		(2 "B.Cu" signal "BOTTOM")
		(9 "F.Adhes" user "F.Adhesive")
		(11 "B.Adhes" user "B.Adhesive")
		(13 "F.Paste" user "Package Geometry/Pastemask Top")
		(15 "B.Paste" user "Package Geometry/Pastemask Bottom")
		(5 "F.SilkS" user "Ref Des/Silkscreen Top")
		(7 "B.SilkS" user "Ref Des/Silkscreen Bottom")
		(1 "F.Mask" user "Board Geometry/Soldermask Top")
		(3 "B.Mask" user "Board Geometry/Soldermask Bottom")
		(17 "Dwgs.User" user "User.Drawings")
		(19 "Cmts.User" user "User.Comments")
		(21 "Eco1.User" user "User.Eco1")
		(23 "Eco2.User" user "User.Eco2")
		(25 "Edge.Cuts" user "Board Geometry/Outline")
		(27 "Margin" user)
		(31 "F.CrtYd" user "Package Geometry/Place Bound Top")
		(29 "B.CrtYd" user "Package Geometry/Place Bound Bottom")
		(35 "F.Fab" user "Ref Des/Assembly Top")
		(33 "B.Fab" user "Ref Des/Assembly Bottom")
	)
	(footprint ""
		(layer "F.Cu")
		(at 273.168872 -73.318116)
		(property "Reference" "C5D48"
			(at 0 0 0)
			(layer "F.SilkS")
			(hide yes)
			(effects
				(font
					(size 1.27 1.27)
				)
			)
		)
		(property "Value" ""
			(at 0 0 0)
			(layer "F.Fab")
			(effects
				(font
					(size 1.27 1.27)
				)
			)
		)
		(duplicate_pad_numbers_are_jumpers no)
		(fp_poly
			(pts
				(xy -0.4953 -0.2032) (xy 0.4953 -0.2032) (xy 0.4953 1.6002) (xy -0.4953 1.6002)
			)
			(stroke
				(width 0)
				(type default)
			)
			(fill no)
			(layer "F.CrtYd")
		)
		(fp_line
			(start -0.4953 -0.2032)
			(end 0.4953 -0.2032)
			(stroke
				(width 0.1)
				(type default)
			)
			(layer "F.Fab")
		)
		(fp_line
			(start -0.4953 1.6002)
			(end -0.4953 -0.2032)
			(stroke
				(width 0.1)
				(type default)
			)
			(layer "F.Fab")
		)
		(fp_line
			(start 0.4953 -0.2032)
			(end 0.4953 1.6002)
			(stroke
				(width 0.1)
				(type default)
			)
			(layer "F.Fab")
		)
		(fp_line
			(start 0.4953 1.6002)
			(end -0.4953 1.6002)
			(stroke
				(width 0.1)
				(type default)
			)
			(layer "F.Fab")
		)
		(pad "1" smd rect
			(at 0 0)
			(size 0.762 0.889)
			(layers "F.Cu" "F.Mask" "F.Paste")
			(net "PVCCMCP_CPU0")
		)
		(pad "2" smd rect
			(at 0 1.397)
			(size 0.762 0.889)
			(layers "F.Cu" "F.Mask" "F.Paste")
			(net "GND")
		)
		(zone
			(layer "F.Cu")
			(hatch none 0.5)
			(connect_pads
				(clearance 0)
			)
			(min_thickness 0.25)
			(keepout
				(tracks not_allowed)
				(vias allowed)
				(pads allowed)
				(copperpour not_allowed)
				(footprints allowed)
			)
			(placement
				(enabled no)
				(sheetname "")
			)
			(fill
				(thermal_gap 0.5)
				(thermal_bridge_width 0.5)
				(island_removal_mode 0)
			)
			(polygon
				(pts
					(xy 272.787872 -72.873616) (xy 273.549872 -72.873616) (xy 273.549872 -72.365616) (xy 272.787872 -72.365616)
				)
			)
		)
	)
	(footprint ""
		(layer "F.Cu")
		(at 465.836 -134.366 180)
		(property "Reference" "R9B9"
			(at 0 0 180)
			(layer "F.SilkS")
			(hide yes)
			(effects
				(font
					(size 1.27 1.27)
				)
			)
		)
		(property "Value" ""
			(at 0 0 180)
			(layer "F.Fab")
			(effects
				(font
					(size 1.27 1.27)
				)
			)
		)
		(duplicate_pad_numbers_are_jumpers no)
		(fp_poly
			(pts
				(xy -0.2794 -0.1016) (xy 0.2794 -0.1016) (xy 0.2794 0.9906) (xy -0.2794 0.9906)
			)
			(stroke
				(width 0)
				(type default)
			)
			(fill no)
			(layer "F.CrtYd")
		)
		(fp_line
			(start 0.2794 0.9906)
			(end 0.2794 -0.1016)
			(stroke
				(width 0.1)
				(type default)
			)
			(layer "F.Fab")
		)
		(fp_line
			(start 0.2794 -0.1016)
			(end -0.2794 -0.1016)
			(stroke
				(width 0.1)
				(type default)
			)
			(layer "F.Fab")
		)
		(fp_line
			(start -0.2794 0.9906)
			(end 0.2794 0.9906)
			(stroke
				(width 0.1)
				(type default)
			)
			(layer "F.Fab")
		)
		(fp_line
			(start -0.2794 -0.1016)
			(end -0.2794 0.9906)
			(stroke
				(width 0.1)
				(type default)
			)
			(layer "F.Fab")
		)
		(pad "1" smd rect
			(at 0 0 180)
			(size 0.508 0.508)
			(layers "F.Cu" "F.Mask" "F.Paste")
			(net "JTAG_MCP_TCK")
		)
		(pad "2" smd rect
			(at 0 0.889 180)
			(size 0.508 0.508)
			(layers "F.Cu" "F.Mask" "F.Paste")
			(net "GND")
		)
		(zone
			(layer "F.Cu")
			(hatch none 0.5)
			(connect_pads
				(clearance 0)
			)
			(min_thickness 0.25)
			(keepout
				(tracks not_allowed)
				(vias allowed)
				(pads allowed)
				(copperpour not_allowed)
				(footprints allowed)
			)
			(placement
				(enabled no)
				(sheetname "")
			)
			(fill
				(thermal_gap 0.5)
				(thermal_bridge_width 0.5)
				(island_removal_mode 0)
			)
			(polygon
				(pts
					(xy 466.09 -135.001) (xy 465.582 -135.001) (xy 465.582 -134.62) (xy 466.09 -134.62)
				)
			)
		)
		(zone
			(layer "F.Cu")
			(hatch none 0.5)
			(connect_pads
				(clearance 0)
			)
			(min_thickness 0.25)
			(keepout
				(tracks allowed)
				(vias not_allowed)
				(pads allowed)
				(copperpour not_allowed)
				(footprints allowed)
			)
			(placement
				(enabled no)
				(sheetname "")
			)
			(fill
				(thermal_gap 0.5)
				(thermal_bridge_width 0.5)
				(island_removal_mode 0)
			)
			(polygon
				(pts
					(xy 466.09 -134.62) (xy 465.582 -134.62) (xy 465.582 -135.001) (xy 466.09 -135.001)
				)
			)
		)
	)
	(footprint ""
		(layer "F.Cu")
		(at 188.2775 -74.295 -90)
		(property "Reference" "RF6"
			(at -0.8382 -0.67818 270)
			(unlocked yes)
			(layer "F.SilkS")
			(effects
				(font
					(size 0.4064 0.254)
					(thickness 0.1524)
				)
				(justify left)
			)
		)
		(property "Value" ""
			(at 0 0 270)
			(layer "F.Fab")
			(effects
				(font
					(size 1.27 1.27)
				)
			)
		)
		(duplicate_pad_numbers_are_jumpers no)
		(fp_poly
			(pts
				(xy -0.2794 -0.1016) (xy 0.2794 -0.1016) (xy 0.2794 0.9906) (xy -0.2794 0.9906)
			)
			(stroke
				(width 0)
				(type default)
			)
			(fill no)
			(layer "F.CrtYd")
		)
		(fp_line
			(start -0.2794 0.9906)
			(end 0.2794 0.9906)
			(stroke
				(width 0.1)
				(type default)
			)
			(layer "F.Fab")
		)
		(fp_line
			(start 0.2794 0.9906)
			(end 0.2794 -0.1016)
			(stroke
				(width 0.1)
				(type default)
			)
			(layer "F.Fab")
		)
		(fp_line
			(start -0.2794 -0.1016)
			(end -0.2794 0.9906)
			(stroke
				(width 0.1)
				(type default)
			)
			(layer "F.Fab")
		)
		(fp_line
			(start 0.2794 -0.1016)
			(end -0.2794 -0.1016)
			(stroke
				(width 0.1)
				(type default)
			)
			(layer "F.Fab")
		)
		(pad "1" smd rect
			(at 0 0 270)
			(size 0.508 0.508)
			(layers "F.Cu" "F.Mask" "F.Paste")
			(net "VR_PVSA_CPU0_BIREF1")
		)
		(pad "2" smd rect
			(at 0 0.889 270)
			(size 0.508 0.508)
			(layers "F.Cu" "F.Mask" "F.Paste")
			(net "ISENSE_PVSA_CPU0_IMON")
		)
		(zone
			(layer "F.Cu")
			(hatch none 0.5)
			(connect_pads
				(clearance 0)
			)
			(min_thickness 0.25)
			(keepout
				(tracks not_allowed)
				(vias allowed)
				(pads allowed)
				(copperpour not_allowed)
				(footprints allowed)
			)
			(placement
				(enabled no)
				(sheetname "")
			)
			(fill
				(thermal_gap 0.5)
				(thermal_bridge_width 0.5)
				(island_removal_mode 0)
			)
			(polygon
				(pts
					(xy 187.6425 -74.549) (xy 187.6425 -74.041) (xy 188.0235 -74.041) (xy 188.0235 -74.549)
				)
			)
		)
		(zone
			(layer "F.Cu")
			(hatch none 0.5)
			(connect_pads
				(clearance 0)
			)
			(min_thickness 0.25)
			(keepout
				(tracks allowed)
				(vias not_allowed)
				(pads allowed)
				(copperpour not_allowed)
				(footprints allowed)
			)
			(placement
				(enabled no)
				(sheetname "")
			)
			(fill
				(thermal_gap 0.5)
				(thermal_bridge_width 0.5)
				(island_removal_mode 0)
			)
			(polygon
				(pts
					(xy 188.0235 -74.549) (xy 188.0235 -74.041) (xy 187.6425 -74.041) (xy 187.6425 -74.549)
				)
			)
		)
	)
)
